(kicad_pcb
	(version 20241229)
	(generator "pcbnew")
	(generator_version "9.0")
	(general
		(thickness 1.599998)
		(legacy_teardrops no)
	)
	(paper "A4")
	(title_block
		(date "2023-02-12")
		(rev "1.1.5")
		(comment 9 "footprints 378-384 of 473")
	)
	(layers
		(0 "F.Cu" signal)
		(4 "In1.Cu" power "In1.GND")
		(6 "In2.Cu" signal)
		(8 "In3.Cu" power "In3.GND")
		(10 "In4.Cu" power "In4.VCC")
		(12 "In5.Cu" signal)
		(14 "In6.Cu" power "In6.VCC")
		(2 "B.Cu" signal)
		(9 "F.Adhes" user "F.Adhesive")
		(11 "B.Adhes" user "B.Adhesive")
		(13 "F.Paste" user)
		(15 "B.Paste" user)
		(5 "F.SilkS" user "F.Silkscreen")
		(7 "B.SilkS" user "B.Silkscreen")
		(1 "F.Mask" user)
		(3 "B.Mask" user)
		(17 "Dwgs.User" user "User.Drawings")
		(19 "Cmts.User" user "User.Comments")
		(21 "Eco1.User" user "User.Eco1")
		(23 "Eco2.User" user "User.Eco2")
		(25 "Edge.Cuts" user)
		(27 "Margin" user)
		(31 "F.CrtYd" user "F.Courtyard")
		(29 "B.CrtYd" user "B.Courtyard")
		(35 "F.Fab" user)
		(33 "B.Fab" user)
	)
	(footprint "antmicro-footprints:C_0402_1005Metric"
		(layer "B.Cu")
		(at 174.5 99.875 180)
		(descr "Capacitor SMD 0402")
		(tags "capacitor SMD 0402")
		(property "Reference" "C50"
			(at -1.1 -1.225 0)
			(layer "B.SilkS")
			(effects
				(font
					(size 0.7 0.7)
					(thickness 0.15)
				)
				(justify left bottom mirror)
			)
		)
		(property "Value" "C_4u7_0402"
			(at 0 -1.4 0)
			(layer "B.Fab")
			(effects
				(font
					(size 0.7 0.7)
					(thickness 0.15)
				)
				(justify left bottom mirror)
			)
		)
		(property "Description" " "
			(at 0 0 180)
			(layer "F.Fab")
			(hide yes)
			(effects
				(font
					(size 1.27 1.27)
					(thickness 0.15)
				)
			)
		)
		(property "Author" "Antmicro"
			(at 349 199.75 0)
			(layer "B.Fab")
			(hide yes)
			(effects
				(font
					(size 1 1)
					(thickness 0.15)
				)
				(justify mirror)
			)
		)
		(property "Dielectric" ""
			(at 349 199.75 0)
			(layer "B.Fab")
			(hide yes)
			(effects
				(font
					(size 1 1)
					(thickness 0.15)
				)
				(justify mirror)
			)
		)
		(property "License" "Apache-2.0"
			(at 349 199.75 0)
			(layer "B.Fab")
			(hide yes)
			(effects
				(font
					(size 1 1)
					(thickness 0.15)
				)
				(justify mirror)
			)
		)
		(property "MPN" "GRM155R61A475MEAAD"
			(at 349 199.75 0)
			(layer "B.Fab")
			(hide yes)
			(effects
				(font
					(size 1 1)
					(thickness 0.15)
				)
				(justify mirror)
			)
		)
		(property "Manufacturer" "Murata"
			(at 349 199.75 0)
			(layer "B.Fab")
			(hide yes)
			(effects
				(font
					(size 1 1)
					(thickness 0.15)
				)
				(justify mirror)
			)
		)
		(property "Val" "4u7"
			(at 349 199.75 0)
			(layer "B.Fab")
			(hide yes)
			(effects
				(font
					(size 1 1)
					(thickness 0.15)
				)
				(justify mirror)
			)
		)
		(property "Voltage" ""
			(at 349 199.75 0)
			(layer "B.Fab")
			(hide yes)
			(effects
				(font
					(size 1 1)
					(thickness 0.15)
				)
				(justify mirror)
			)
		)
		(sheetname "FPGA power")
		(sheetfile "fpga-power.kicad_sch")
		(attr smd)
		(fp_rect
			(start -0.94 0.47)
			(end 0.94 -0.47)
			(stroke
				(width 0.05)
				(type solid)
			)
			(fill no)
			(layer "B.CrtYd")
		)
		(fp_rect
			(start -0.499 0.249)
			(end 0.499 -0.249)
			(stroke
				(width 0.15)
				(type solid)
			)
			(fill no)
			(layer "B.Fab")
		)
		(pad "1" smd roundrect
			(at -0.484 0 180)
			(size 0.59 0.64)
			(layers "B.Cu" "B.Mask" "B.Paste")
			(roundrect_rratio 0.25)
			(net 459 "3V3_SYS")
			(pintype "passive")
		)
		(pad "2" smd roundrect
			(at 0.484 0 180)
			(size 0.59 0.64)
			(layers "B.Cu" "B.Mask" "B.Paste")
			(roundrect_rratio 0.25)
			(net 5 "GND")
			(pintype "passive")
		)
	)
	(footprint "antmicro-footprints:C_0402_1005Metric"
		(layer "B.Cu")
		(at 173.5 101.75)
		(descr "Capacitor SMD 0402")
		(tags "capacitor SMD 0402")
		(property "Reference" "C54"
			(at 3 0.45 180)
			(layer "B.SilkS")
			(effects
				(font
					(size 0.7 0.7)
					(thickness 0.15)
				)
				(justify left bottom mirror)
			)
		)
		(property "Value" "C_4u7_0402"
			(at 0 -1.4 180)
			(layer "B.Fab")
			(effects
				(font
					(size 0.7 0.7)
					(thickness 0.15)
				)
				(justify left bottom mirror)
			)
		)
		(property "Description" " "
			(at 0 0 0)
			(layer "F.Fab")
			(hide yes)
			(effects
				(font
					(size 1.27 1.27)
					(thickness 0.15)
				)
			)
		)
		(property "Author" "Antmicro"
			(at 0 0 0)
			(layer "B.Fab")
			(hide yes)
			(effects
				(font
					(size 1 1)
					(thickness 0.15)
				)
				(justify mirror)
			)
		)
		(property "Dielectric" ""
			(at 0 0 0)
			(layer "B.Fab")
			(hide yes)
			(effects
				(font
					(size 1 1)
					(thickness 0.15)
				)
				(justify mirror)
			)
		)
		(property "License" "Apache-2.0"
			(at 0 0 0)
			(layer "B.Fab")
			(hide yes)
			(effects
				(font
					(size 1 1)
					(thickness 0.15)
				)
				(justify mirror)
			)
		)
		(property "MPN" "GRM155R61A475MEAAD"
			(at 0 0 0)
			(layer "B.Fab")
			(hide yes)
			(effects
				(font
					(size 1 1)
					(thickness 0.15)
				)
				(justify mirror)
			)
		)
		(property "Manufacturer" "Murata"
			(at 0 0 0)
			(layer "B.Fab")
			(hide yes)
			(effects
				(font
					(size 1 1)
					(thickness 0.15)
				)
				(justify mirror)
			)
		)
		(property "Val" "4u7"
			(at 0 0 0)
			(layer "B.Fab")
			(hide yes)
			(effects
				(font
					(size 1 1)
					(thickness 0.15)
				)
				(justify mirror)
			)
		)
		(property "Voltage" ""
			(at 0 0 0)
			(layer "B.Fab")
			(hide yes)
			(effects
				(font
					(size 1 1)
					(thickness 0.15)
				)
				(justify mirror)
			)
		)
		(sheetname "FPGA power")
		(sheetfile "fpga-power.kicad_sch")
		(attr smd)
		(fp_rect
			(start -0.94 0.47)
			(end 0.94 -0.47)
			(stroke
				(width 0.05)
				(type solid)
			)
			(fill no)
			(layer "B.CrtYd")
		)
		(fp_rect
			(start -0.499 0.249)
			(end 0.499 -0.249)
			(stroke
				(width 0.15)
				(type solid)
			)
			(fill no)
			(layer "B.Fab")
		)
		(pad "1" smd roundrect
			(at -0.484 0)
			(size 0.59 0.64)
			(layers "B.Cu" "B.Mask" "B.Paste")
			(roundrect_rratio 0.25)
			(net 459 "3V3_SYS")
			(pintype "passive")
		)
		(pad "2" smd roundrect
			(at 0.484 0)
			(size 0.59 0.64)
			(layers "B.Cu" "B.Mask" "B.Paste")
			(roundrect_rratio 0.25)
			(net 5 "GND")
			(pintype "passive")
		)
	)
	(footprint "antmicro-footprints:C_0402_1005Metric"
		(layer "B.Cu")
		(at 174.5 103.125)
		(descr "Capacitor SMD 0402")
		(tags "capacitor SMD 0402")
		(property "Reference" "C58"
			(at 1.1 1.275 180)
			(layer "B.SilkS")
			(effects
				(font
					(size 0.7 0.7)
					(thickness 0.15)
				)
				(justify left bottom mirror)
			)
		)
		(property "Value" "C_4u7_0402"
			(at 0 -1.4 180)
			(layer "B.Fab")
			(effects
				(font
					(size 0.7 0.7)
					(thickness 0.15)
				)
				(justify left bottom mirror)
			)
		)
		(property "Description" " "
			(at 0 0 0)
			(layer "F.Fab")
			(hide yes)
			(effects
				(font
					(size 1.27 1.27)
					(thickness 0.15)
				)
			)
		)
		(property "Author" "Antmicro"
			(at 0 0 0)
			(layer "B.Fab")
			(hide yes)
			(effects
				(font
					(size 1 1)
					(thickness 0.15)
				)
				(justify mirror)
			)
		)
		(property "Dielectric" ""
			(at 0 0 0)
			(layer "B.Fab")
			(hide yes)
			(effects
				(font
					(size 1 1)
					(thickness 0.15)
				)
				(justify mirror)
			)
		)
		(property "License" "Apache-2.0"
			(at 0 0 0)
			(layer "B.Fab")
			(hide yes)
			(effects
				(font
					(size 1 1)
					(thickness 0.15)
				)
				(justify mirror)
			)
		)
		(property "MPN" "GRM155R61A475MEAAD"
			(at 0 0 0)
			(layer "B.Fab")
			(hide yes)
			(effects
				(font
					(size 1 1)
					(thickness 0.15)
				)
				(justify mirror)
			)
		)
		(property "Manufacturer" "Murata"
			(at 0 0 0)
			(layer "B.Fab")
			(hide yes)
			(effects
				(font
					(size 1 1)
					(thickness 0.15)
				)
				(justify mirror)
			)
		)
		(property "Val" "4u7"
			(at 0 0 0)
			(layer "B.Fab")
			(hide yes)
			(effects
				(font
					(size 1 1)
					(thickness 0.15)
				)
				(justify mirror)
			)
		)
		(property "Voltage" ""
			(at 0 0 0)
			(layer "B.Fab")
			(hide yes)
			(effects
				(font
					(size 1 1)
					(thickness 0.15)
				)
				(justify mirror)
			)
		)
		(sheetname "FPGA power")
		(sheetfile "fpga-power.kicad_sch")
		(attr smd)
		(fp_rect
			(start -0.94 0.47)
			(end 0.94 -0.47)
			(stroke
				(width 0.05)
				(type solid)
			)
			(fill no)
			(layer "B.CrtYd")
		)
		(fp_rect
			(start -0.499 0.249)
			(end 0.499 -0.249)
			(stroke
				(width 0.15)
				(type solid)
			)
			(fill no)
			(layer "B.Fab")
		)
		(pad "1" smd roundrect
			(at -0.484 0)
			(size 0.59 0.64)
			(layers "B.Cu" "B.Mask" "B.Paste")
			(roundrect_rratio 0.25)
			(net 459 "3V3_SYS")
			(pintype "passive")
		)
		(pad "2" smd roundrect
			(at 0.484 0)
			(size 0.59 0.64)
			(layers "B.Cu" "B.Mask" "B.Paste")
			(roundrect_rratio 0.25)
			(net 5 "GND")
			(pintype "passive")
		)
	)
	(footprint "antmicro-footprints:C_0402_1005Metric"
		(layer "B.Cu")
		(at 170.5 102.75)
		(descr "Capacitor SMD 0402")
		(tags "capacitor SMD 0402")
		(property "Reference" "C64"
			(at 1.1 1.25 180)
			(layer "B.SilkS")
			(effects
				(font
					(size 0.7 0.7)
					(thickness 0.15)
				)
				(justify left bottom mirror)
			)
		)
		(property "Value" "C_4u7_0402"
			(at 0 -1.4 180)
			(layer "B.Fab")
			(effects
				(font
					(size 0.7 0.7)
					(thickness 0.15)
				)
				(justify left bottom mirror)
			)
		)
		(property "Description" " "
			(at 0 0 0)
			(layer "F.Fab")
			(hide yes)
			(effects
				(font
					(size 1.27 1.27)
					(thickness 0.15)
				)
			)
		)
		(property "Author" "Antmicro"
			(at 0 0 0)
			(layer "B.Fab")
			(hide yes)
			(effects
				(font
					(size 1 1)
					(thickness 0.15)
				)
				(justify mirror)
			)
		)
		(property "Dielectric" ""
			(at 0 0 0)
			(layer "B.Fab")
			(hide yes)
			(effects
				(font
					(size 1 1)
					(thickness 0.15)
				)
				(justify mirror)
			)
		)
		(property "License" "Apache-2.0"
			(at 0 0 0)
			(layer "B.Fab")
			(hide yes)
			(effects
				(font
					(size 1 1)
					(thickness 0.15)
				)
				(justify mirror)
			)
		)
		(property "MPN" "GRM155R61A475MEAAD"
			(at 0 0 0)
			(layer "B.Fab")
			(hide yes)
			(effects
				(font
					(size 1 1)
					(thickness 0.15)
				)
				(justify mirror)
			)
		)
		(property "Manufacturer" "Murata"
			(at 0 0 0)
			(layer "B.Fab")
			(hide yes)
			(effects
				(font
					(size 1 1)
					(thickness 0.15)
				)
				(justify mirror)
			)
		)
		(property "Val" "4u7"
			(at 0 0 0)
			(layer "B.Fab")
			(hide yes)
			(effects
				(font
					(size 1 1)
					(thickness 0.15)
				)
				(justify mirror)
			)
		)
		(property "Voltage" ""
			(at 0 0 0)
			(layer "B.Fab")
			(hide yes)
			(effects
				(font
					(size 1 1)
					(thickness 0.15)
				)
				(justify mirror)
			)
		)
		(sheetname "FPGA power")
		(sheetfile "fpga-power.kicad_sch")
		(attr smd)
		(fp_rect
			(start -0.94 0.47)
			(end 0.94 -0.47)
			(stroke
				(width 0.05)
				(type solid)
			)
			(fill no)
			(layer "B.CrtYd")
		)
		(fp_rect
			(start -0.499 0.249)
			(end 0.499 -0.249)
			(stroke
				(width 0.15)
				(type solid)
			)
			(fill no)
			(layer "B.Fab")
		)
		(pad "1" smd roundrect
			(at -0.484 0)
			(size 0.59 0.64)
			(layers "B.Cu" "B.Mask" "B.Paste")
			(roundrect_rratio 0.25)
			(net 459 "3V3_SYS")
			(pintype "passive")
		)
		(pad "2" smd roundrect
			(at 0.484 0)
			(size 0.59 0.64)
			(layers "B.Cu" "B.Mask" "B.Paste")
			(roundrect_rratio 0.25)
			(net 5 "GND")
			(pintype "passive")
		)
	)
	(footprint "antmicro-footprints:C_0402_1005Metric"
		(layer "B.Cu")
		(at 167.5 102.125)
		(descr "Capacitor SMD 0402")
		(tags "capacitor SMD 0402")
		(property "Reference" "C68"
			(at 1.1 1.175 180)
			(layer "B.SilkS")
			(effects
				(font
					(size 0.7 0.7)
					(thickness 0.15)
				)
				(justify left bottom mirror)
			)
		)
		(property "Value" "C_4u7_0402"
			(at 0 -1.4 180)
			(layer "B.Fab")
			(effects
				(font
					(size 0.7 0.7)
					(thickness 0.15)
				)
				(justify left bottom mirror)
			)
		)
		(property "Description" " "
			(at 0 0 0)
			(layer "F.Fab")
			(hide yes)
			(effects
				(font
					(size 1.27 1.27)
					(thickness 0.15)
				)
			)
		)
		(property "Author" "Antmicro"
			(at 0 0 0)
			(layer "B.Fab")
			(hide yes)
			(effects
				(font
					(size 1 1)
					(thickness 0.15)
				)
				(justify mirror)
			)
		)
		(property "Dielectric" ""
			(at 0 0 0)
			(layer "B.Fab")
			(hide yes)
			(effects
				(font
					(size 1 1)
					(thickness 0.15)
				)
				(justify mirror)
			)
		)
		(property "License" "Apache-2.0"
			(at 0 0 0)
			(layer "B.Fab")
			(hide yes)
			(effects
				(font
					(size 1 1)
					(thickness 0.15)
				)
				(justify mirror)
			)
		)
		(property "MPN" "GRM155R61A475MEAAD"
			(at 0 0 0)
			(layer "B.Fab")
			(hide yes)
			(effects
				(font
					(size 1 1)
					(thickness 0.15)
				)
				(justify mirror)
			)
		)
		(property "Manufacturer" "Murata"
			(at 0 0 0)
			(layer "B.Fab")
			(hide yes)
			(effects
				(font
					(size 1 1)
					(thickness 0.15)
				)
				(justify mirror)
			)
		)
		(property "Val" "4u7"
			(at 0 0 0)
			(layer "B.Fab")
			(hide yes)
			(effects
				(font
					(size 1 1)
					(thickness 0.15)
				)
				(justify mirror)
			)
		)
		(property "Voltage" ""
			(at 0 0 0)
			(layer "B.Fab")
			(hide yes)
			(effects
				(font
					(size 1 1)
					(thickness 0.15)
				)
				(justify mirror)
			)
		)
		(sheetname "FPGA power")
		(sheetfile "fpga-power.kicad_sch")
		(attr smd)
		(fp_rect
			(start -0.94 0.47)
			(end 0.94 -0.47)
			(stroke
				(width 0.05)
				(type solid)
			)
			(fill no)
			(layer "B.CrtYd")
		)
		(fp_rect
			(start -0.499 0.249)
			(end 0.499 -0.249)
			(stroke
				(width 0.15)
				(type solid)
			)
			(fill no)
			(layer "B.Fab")
		)
		(pad "1" smd roundrect
			(at -0.484 0)
			(size 0.59 0.64)
			(layers "B.Cu" "B.Mask" "B.Paste")
			(roundrect_rratio 0.25)
			(net 459 "3V3_SYS")
			(pintype "passive")
		)
		(pad "2" smd roundrect
			(at 0.484 0)
			(size 0.59 0.64)
			(layers "B.Cu" "B.Mask" "B.Paste")
			(roundrect_rratio 0.25)
			(net 5 "GND")
			(pintype "passive")
		)
	)
	(footprint "antmicro-footprints:C_0402_1005Metric"
		(layer "B.Cu")
		(at 164.875 102.5 90)
		(descr "Capacitor SMD 0402")
		(tags "capacitor SMD 0402")
		(property "Reference" "C72"
			(at 1.1 -0.475 270)
			(layer "B.SilkS")
			(effects
				(font
					(size 0.7 0.7)
					(thickness 0.15)
				)
				(justify left bottom mirror)
			)
		)
		(property "Value" "C_4u7_0402"
			(at 0 -1.4 270)
			(layer "B.Fab")
			(effects
				(font
					(size 0.7 0.7)
					(thickness 0.15)
				)
				(justify left bottom mirror)
			)
		)
		(property "Description" " "
			(at 0 0 90)
			(layer "F.Fab")
			(hide yes)
			(effects
				(font
					(size 1.27 1.27)
					(thickness 0.15)
				)
			)
		)
		(property "Author" "Antmicro"
			(at 267.375 -62.375 0)
			(layer "B.Fab")
			(hide yes)
			(effects
				(font
					(size 1 1)
					(thickness 0.15)
				)
				(justify mirror)
			)
		)
		(property "Dielectric" ""
			(at 267.375 -62.375 0)
			(layer "B.Fab")
			(hide yes)
			(effects
				(font
					(size 1 1)
					(thickness 0.15)
				)
				(justify mirror)
			)
		)
		(property "License" "Apache-2.0"
			(at 267.375 -62.375 0)
			(layer "B.Fab")
			(hide yes)
			(effects
				(font
					(size 1 1)
					(thickness 0.15)
				)
				(justify mirror)
			)
		)
		(property "MPN" "GRM155R61A475MEAAD"
			(at 267.375 -62.375 0)
			(layer "B.Fab")
			(hide yes)
			(effects
				(font
					(size 1 1)
					(thickness 0.15)
				)
				(justify mirror)
			)
		)
		(property "Manufacturer" "Murata"
			(at 267.375 -62.375 0)
			(layer "B.Fab")
			(hide yes)
			(effects
				(font
					(size 1 1)
					(thickness 0.15)
				)
				(justify mirror)
			)
		)
		(property "Val" "4u7"
			(at 267.375 -62.375 0)
			(layer "B.Fab")
			(hide yes)
			(effects
				(font
					(size 1 1)
					(thickness 0.15)
				)
				(justify mirror)
			)
		)
		(property "Voltage" ""
			(at 267.375 -62.375 0)
			(layer "B.Fab")
			(hide yes)
			(effects
				(font
					(size 1 1)
					(thickness 0.15)
				)
				(justify mirror)
			)
		)
		(sheetname "FPGA power")
		(sheetfile "fpga-power.kicad_sch")
		(attr smd)
		(fp_rect
			(start -0.94 0.47)
			(end 0.94 -0.47)
			(stroke
				(width 0.05)
				(type solid)
			)
			(fill no)
			(layer "B.CrtYd")
		)
		(fp_rect
			(start -0.499 0.249)
			(end 0.499 -0.249)
			(stroke
				(width 0.15)
				(type solid)
			)
			(fill no)
			(layer "B.Fab")
		)
		(pad "1" smd roundrect
			(at -0.484 0 90)
			(size 0.59 0.64)
			(layers "B.Cu" "B.Mask" "B.Paste")
			(roundrect_rratio 0.25)
			(net 459 "3V3_SYS")
			(pintype "passive")
		)
		(pad "2" smd roundrect
			(at 0.484 0 90)
			(size 0.59 0.64)
			(layers "B.Cu" "B.Mask" "B.Paste")
			(roundrect_rratio 0.25)
			(net 5 "GND")
			(pintype "passive")
		)
	)
	(footprint "antmicro-footprints:C_0402_1005Metric"
		(layer "B.Cu")
		(at 166.5 104.125 180)
		(descr "Capacitor SMD 0402")
		(tags "capacitor SMD 0402")
		(property "Reference" "C77"
			(at -1.1 -1.275 0)
			(layer "B.SilkS")
			(effects
				(font
					(size 0.7 0.7)
					(thickness 0.15)
				)
				(justify left bottom mirror)
			)
		)
		(property "Value" "C_4u7_0402"
			(at 0 -1.4 0)
			(layer "B.Fab")
			(effects
				(font
					(size 0.7 0.7)
					(thickness 0.15)
				)
				(justify left bottom mirror)
			)
		)
		(property "Description" " "
			(at 0 0 180)
			(layer "F.Fab")
			(hide yes)
			(effects
				(font
					(size 1.27 1.27)
					(thickness 0.15)
				)
			)
		)
		(property "Author" "Antmicro"
			(at 333 208.25 0)
			(layer "B.Fab")
			(hide yes)
			(effects
				(font
					(size 1 1)
					(thickness 0.15)
				)
				(justify mirror)
			)
		)
		(property "Dielectric" ""
			(at 333 208.25 0)
			(layer "B.Fab")
			(hide yes)
			(effects
				(font
					(size 1 1)
					(thickness 0.15)
				)
				(justify mirror)
			)
		)
		(property "License" "Apache-2.0"
			(at 333 208.25 0)
			(layer "B.Fab")
			(hide yes)
			(effects
				(font
					(size 1 1)
					(thickness 0.15)
				)
				(justify mirror)
			)
		)
		(property "MPN" "GRM155R61A475MEAAD"
			(at 333 208.25 0)
			(layer "B.Fab")
			(hide yes)
			(effects
				(font
					(size 1 1)
					(thickness 0.15)
				)
				(justify mirror)
			)
		)
		(property "Manufacturer" "Murata"
			(at 333 208.25 0)
			(layer "B.Fab")
			(hide yes)
			(effects
				(font
					(size 1 1)
					(thickness 0.15)
				)
				(justify mirror)
			)
		)
		(property "Val" "4u7"
			(at 333 208.25 0)
			(layer "B.Fab")
			(hide yes)
			(effects
				(font
					(size 1 1)
					(thickness 0.15)
				)
				(justify mirror)
			)
		)
		(property "Voltage" ""
			(at 333 208.25 0)
			(layer "B.Fab")
			(hide yes)
			(effects
				(font
					(size 1 1)
					(thickness 0.15)
				)
				(justify mirror)
			)
		)
		(sheetname "FPGA power")
		(sheetfile "fpga-power.kicad_sch")
		(attr smd)
		(fp_rect
			(start -0.94 0.47)
			(end 0.94 -0.47)
			(stroke
				(width 0.05)
				(type solid)
			)
			(fill no)
			(layer "B.CrtYd")
		)
		(fp_rect
			(start -0.499 0.249)
			(end 0.499 -0.249)
			(stroke
				(width 0.15)
				(type solid)
			)
			(fill no)
			(layer "B.Fab")
		)
		(pad "1" smd roundrect
			(at -0.484 0 180)
			(size 0.59 0.64)
			(layers "B.Cu" "B.Mask" "B.Paste")
			(roundrect_rratio 0.25)
			(net 459 "3V3_SYS")
			(pintype "passive")
		)
		(pad "2" smd roundrect
			(at 0.484 0 180)
			(size 0.59 0.64)
			(layers "B.Cu" "B.Mask" "B.Paste")
			(roundrect_rratio 0.25)
			(net 5 "GND")
			(pintype "passive")
		)
	)
)
